FILE_TYPE = CONNECTIVITY;
{Allegro Design Entry HDL 17.4-2019 S026 (4007227) 1/17/2022}
"PAGE_NUMBER" = 436;
0"NC";
END.
